# T6G (Grand Teton) — schematic netlist excerpt (pin names and nets, part order shuffled) for the footprints in the layout excerpt that follows; sources: Cadence DE-HDL packaged netlist, KiCad conversion of 04192023_DAF0TMB3IC0_F0TG_MB_C_brd_V02_OCP.brd

PC112_C1P0_3  Q_CAP  2.2UF 10V 10% X6S  pkg C0402  page 202 : A = PVDDCR_CPU1_P0_PVCC ; B = GND
R3624  Q_RES  4.7K 1% CHIP  pkg 0402LF  page 237 : A = P3V3_AUX ; B = INA230_5_A1

(kicad_pcb
	(version 20260206)
	(generator "pcbnew")
	(generator_version "10.0")
	(general
		(thickness 1.6)
		(legacy_teardrops no)
	)
	(paper "A4")
	(title_block
		(title "04192023_DAF0TMB3IC0_F0TG_MB_C_brd_V02_OCP.brd")
		(comment 1 "Grand Teton / footprints 696-697 of 8354")
	)
	(layers
		(0 "F.Cu" signal "TOP")
		(4 "In1.Cu" signal "GND")
		(6 "In2.Cu" signal "IN1")
		(8 "In3.Cu" signal "GND1")
		(10 "In4.Cu" signal "IN2")
		(12 "In5.Cu" signal "GND2")
		(14 "In6.Cu" signal "IN3")
		(16 "In7.Cu" signal "GND3")
		(18 "In8.Cu" signal "VCC")
		(20 "In9.Cu" signal "VCC1")
		(22 "In10.Cu" signal "GND4")
		(24 "In11.Cu" signal "IN4")
		(26 "In12.Cu" signal "GND5")
		(28 "In13.Cu" signal "IN5")
		(30 "In14.Cu" signal "GND6")
		(32 "In15.Cu" signal "IN6")
		(34 "In16.Cu" signal "GND7")
		(2 "B.Cu" signal "BOTTOM")
		(9 "F.Adhes" user "F.Adhesive")
		(11 "B.Adhes" user "B.Adhesive")
		(13 "F.Paste" user "Package Geometry/Pastemask Top")
		(15 "B.Paste" user "Package Geometry/Pastemask Bottom")
		(5 "F.SilkS" user "Ref Des/Silkscreen Top")
		(7 "B.SilkS" user "Ref Des/Silkscreen Bottom")
		(1 "F.Mask" user "Board Geometry/Soldermask Top")
		(3 "B.Mask" user "Board Geometry/Soldermask Bottom")
		(17 "Dwgs.User" user "User.Drawings")
		(19 "Cmts.User" user "User.Comments")
		(21 "Eco1.User" user "User.Eco1")
		(23 "Eco2.User" user "User.Eco2")
		(25 "Edge.Cuts" user "Board Geometry/Outline")
		(27 "Margin" user)
		(31 "F.CrtYd" user "Package Geometry/Place Bound Top")
		(29 "B.CrtYd" user "Package Geometry/Place Bound Bottom")
		(35 "F.Fab" user "Ref Des/Assembly Top")
		(33 "B.Fab" user "Ref Des/Assembly Bottom")
	)
	(footprint ""
		(layer "F.Cu")
		(at 209.070956 -30.276292 90)
		(property "Reference" "R3624"
			(at 0 0 90)
			(layer "F.SilkS")
			(hide yes)
			(effects
				(font
					(size 1.27 1.27)
				)
			)
		)
		(property "Value" ""
			(at 0 0 90)
			(layer "F.Fab")
			(effects
				(font
					(size 1.27 1.27)
				)
			)
		)
		(duplicate_pad_numbers_are_jumpers no)
		(fp_line
			(start 0.7874 -0.4064)
			(end 0.7874 0.4064)
			(stroke
				(width 0.1524)
				(type default)
			)
			(layer "F.SilkS")
		)
		(fp_line
			(start -0.7874 -0.4064)
			(end 0.7874 -0.4064)
			(stroke
				(width 0.1524)
				(type default)
			)
			(layer "F.SilkS")
		)
		(fp_line
			(start 0.7874 0.4064)
			(end -0.7874 0.4064)
			(stroke
				(width 0.1524)
				(type default)
			)
			(layer "F.SilkS")
		)
		(fp_line
			(start -0.7874 0.4064)
			(end -0.7874 -0.4064)
			(stroke
				(width 0.1524)
				(type default)
			)
			(layer "F.SilkS")
		)
		(fp_line
			(start -0.12065 -0.305054)
			(end -0.12065 -0.2794)
			(stroke
				(width 0.1)
				(type default)
			)
			(layer "F.Fab")
		)
		(fp_line
			(start -0.67945 -0.305054)
			(end -0.12065 -0.305054)
			(stroke
				(width 0.1)
				(type default)
			)
			(layer "F.Fab")
		)
		(fp_line
			(start 0.67945 -0.3048)
			(end 0.67945 0.3048)
			(stroke
				(width 0.1)
				(type default)
			)
			(layer "F.Fab")
		)
		(fp_line
			(start 0.12065 -0.3048)
			(end 0.67945 -0.3048)
			(stroke
				(width 0.1)
				(type default)
			)
			(layer "F.Fab")
		)
		(fp_line
			(start 0.12065 -0.2794)
			(end 0.12065 -0.3048)
			(stroke
				(width 0.1)
				(type default)
			)
			(layer "F.Fab")
		)
		(fp_line
			(start -0.12065 -0.2794)
			(end 0.12065 -0.2794)
			(stroke
				(width 0.1)
				(type default)
			)
			(layer "F.Fab")
		)
		(fp_line
			(start 0.120396 0.2794)
			(end -0.12065 0.2794)
			(stroke
				(width 0.1)
				(type default)
			)
			(layer "F.Fab")
		)
		(fp_line
			(start -0.12065 0.2794)
			(end -0.12065 0.3048)
			(stroke
				(width 0.1)
				(type default)
			)
			(layer "F.Fab")
		)
		(fp_line
			(start 0.67945 0.3048)
			(end 0.120396 0.3048)
			(stroke
				(width 0.1)
				(type default)
			)
			(layer "F.Fab")
		)
		(fp_line
			(start 0.120396 0.3048)
			(end 0.120396 0.2794)
			(stroke
				(width 0.1)
				(type default)
			)
			(layer "F.Fab")
		)
		(fp_line
			(start -0.12065 0.3048)
			(end -0.67945 0.3048)
			(stroke
				(width 0.1)
				(type default)
			)
			(layer "F.Fab")
		)
		(fp_line
			(start -0.67945 0.3048)
			(end -0.67945 -0.305054)
			(stroke
				(width 0.1)
				(type default)
			)
			(layer "F.Fab")
		)
		(pad "1" smd circle
			(at -0.40005 0 90)
			(size 0 0)
			(layers "F.Cu" "F.Mask" "F.Paste")
			(net "P3V3_AUX")
		)
		(pad "2" smd circle
			(at 0.40005 0 90)
			(size 0 0)
			(layers "F.Cu" "F.Mask" "F.Paste")
			(net "INA230_5_A1")
		)
	)
	(footprint ""
		(layer "F.Cu")
		(at 314.66282 -334.993488 -90)
		(property "Reference" "PC112_C1P0_3"
			(at 0 0 270)
			(layer "F.SilkS")
			(hide yes)
			(effects
				(font
					(size 1.27 1.27)
				)
			)
		)
		(property "Value" ""
			(at 0 0 270)
			(layer "F.Fab")
			(effects
				(font
					(size 1.27 1.27)
				)
			)
		)
		(duplicate_pad_numbers_are_jumpers no)
		(fp_line
			(start -0.7874 0.4064)
			(end -0.7874 -0.4064)
			(stroke
				(width 0.1524)
				(type default)
			)
			(layer "F.SilkS")
		)
		(fp_line
			(start 0.7874 0.4064)
			(end -0.7874 0.4064)
			(stroke
				(width 0.1524)
				(type default)
			)
			(layer "F.SilkS")
		)
		(fp_line
			(start -0.7874 -0.4064)
			(end 0.7874 -0.4064)
			(stroke
				(width 0.1524)
				(type default)
			)
			(layer "F.SilkS")
		)
		(fp_line
			(start 0.7874 -0.4064)
			(end 0.7874 0.4064)
			(stroke
				(width 0.1524)
				(type default)
			)
			(layer "F.SilkS")
		)
		(fp_line
			(start -0.67945 0.3048)
			(end -0.67945 -0.305054)
			(stroke
				(width 0.1)
				(type default)
			)
			(layer "F.Fab")
		)
		(fp_line
			(start -0.12065 0.3048)
			(end -0.67945 0.3048)
			(stroke
				(width 0.1)
				(type default)
			)
			(layer "F.Fab")
		)
		(fp_line
			(start 0.120396 0.3048)
			(end 0.120396 0.2794)
			(stroke
				(width 0.1)
				(type default)
			)
			(layer "F.Fab")
		)
		(fp_line
			(start 0.67945 0.3048)
			(end 0.120396 0.3048)
			(stroke
				(width 0.1)
				(type default)
			)
			(layer "F.Fab")
		)
		(fp_line
			(start -0.12065 0.2794)
			(end -0.12065 0.3048)
			(stroke
				(width 0.1)
				(type default)
			)
			(layer "F.Fab")
		)
		(fp_line
			(start 0.120396 0.2794)
			(end -0.12065 0.2794)
			(stroke
				(width 0.1)
				(type default)
			)
			(layer "F.Fab")
		)
		(fp_line
			(start -0.12065 -0.2794)
			(end 0.12065 -0.2794)
			(stroke
				(width 0.1)
				(type default)
			)
			(layer "F.Fab")
		)
		(fp_line
			(start 0.12065 -0.2794)
			(end 0.12065 -0.3048)
			(stroke
				(width 0.1)
				(type default)
			)
			(layer "F.Fab")
		)
		(fp_line
			(start 0.12065 -0.3048)
			(end 0.67945 -0.3048)
			(stroke
				(width 0.1)
				(type default)
			)
			(layer "F.Fab")
		)
		(fp_line
			(start 0.67945 -0.3048)
			(end 0.67945 0.3048)
			(stroke
				(width 0.1)
				(type default)
			)
			(layer "F.Fab")
		)
		(fp_line
			(start -0.67945 -0.305054)
			(end -0.12065 -0.305054)
			(stroke
				(width 0.1)
				(type default)
			)
			(layer "F.Fab")
		)
		(fp_line
			(start -0.12065 -0.305054)
			(end -0.12065 -0.2794)
			(stroke
				(width 0.1)
				(type default)
			)
			(layer "F.Fab")
		)
		(pad "1" smd circle
			(at -0.40005 0 270)
			(size 0 0)
			(layers "F.Cu" "F.Mask" "F.Paste")
			(net "PVDDCR_CPU1_P0_PVCC")
		)
		(pad "2" smd circle
			(at 0.40005 0 270)
			(size 0 0)
			(layers "F.Cu" "F.Mask" "F.Paste")
			(net "GND")
		)
	)
)
